(kicad_pcb
	(version 20221018)
	(generator pcbnew)
	(general
    (thickness 1.518)
  )
	(paper "A4")
	(title_block
    (title "Kria K26 Devboard")
    (date "2024-03-26")
    (rev "1.2.5")
    (comment 1 "www.antmicro.com")
    (comment 2 "Antmicro Ltd.")
		(comment 9 "footprints 168-173 of 660")
	)
	(layers
    (0 "F.Cu" mixed)
    (1 "In1.Cu" power)
    (2 "In2.Cu" mixed)
    (3 "In3.Cu" power)
    (4 "In4.Cu" mixed)
    (5 "In5.Cu" power)
    (6 "In6.Cu" mixed)
    (31 "B.Cu" power)
    (32 "B.Adhes" user "B.Adhesive")
    (33 "F.Adhes" user "F.Adhesive")
    (34 "B.Paste" user)
    (35 "F.Paste" user)
    (36 "B.SilkS" user "B.Silkscreen")
    (37 "F.SilkS" user "F.Silkscreen")
    (38 "B.Mask" user)
    (39 "F.Mask" user)
    (40 "Dwgs.User" user "User.Drawings")
    (41 "Cmts.User" user "User.Comments")
    (42 "Eco1.User" user "User.Eco1")
    (43 "Eco2.User" user "User.Eco2")
    (44 "Edge.Cuts" user)
    (45 "Margin" user)
    (46 "B.CrtYd" user "B.Courtyard")
    (47 "F.CrtYd" user "F.Courtyard")
    (48 "B.Fab" user)
    (49 "F.Fab" user)
  )
	(footprint "kria-k26-devboard-footprints:C_0402_1005Metric" (layer "F.Cu")
    (at 111.625 75.145 90)
    (descr "Capacitor SMD 0402")
    (tags "capacitor SMD 0402")
    (property "Author" "Antmicro")
    (property "Dielectric" "X5R")
    (property "License" "Apache-2.0")
    (property "MPN" "GRM155R61H104KE14D")
    (property "Manufacturer" "Murata")
    (property "Sheetfile" "usb.kicad_sch")
    (property "Sheetname" "USB")
    (property "Val" "100n")
    (property "Voltage" "50V")
    (property "ki_description" " ")
    (attr smd)
    (fp_text reference "C77" (at -3.055 0.385 90) (layer "F.SilkS")
        (effects (font (size 0.7 0.7) (thickness 0.15)) (justify left bottom))
    )
    (fp_text value "C_100n_0402" (at 0 1.4 90) (layer "F.Fab") hide
        (effects (font (size 0.7 0.7) (thickness 0.15)) (justify left bottom))
    )
    (fp_text user "License: Apache-2.0" (at -0.932 5.17 90) (layer "F.Fab") hide
        (effects (font (size 0.7 0.7) (thickness 0.15)) (justify left bottom))
    )
    (fp_text user "Author: Antmicro" (at -0.932 4.17 90) (layer "F.Fab") hide
        (effects (font (size 0.7 0.7) (thickness 0.15)) (justify left bottom))
    )
    (fp_text user "${REFERENCE}" (at -0.932 3.168 90) (layer "F.Fab") hide
        (effects (font (size 0.7 0.7) (thickness 0.15)) (justify left bottom))
    )
    (fp_rect (start -0.94 -0.47) (end 0.94 0.47)
      (stroke (width 0.05) (type solid)) (fill none) (layer "F.CrtYd"))
    (fp_rect (start -0.499 -0.249) (end 0.499 0.249)
      (stroke (width 0.15) (type solid)) (fill none) (layer "F.Fab"))
    (pad "1" smd roundrect (at -0.484 0 90) (size 0.59 0.64) (layers "F.Cu" "F.Paste" "F.Mask") (roundrect_rratio 0.25)
      (net 76 "/USB/USB4_TX_P") (pintype "passive"))
    (pad "2" smd roundrect (at 0.484 0 90) (size 0.59 0.64) (layers "F.Cu" "F.Paste" "F.Mask") (roundrect_rratio 0.25)
      (net 285 "/USB/USB4_TX_C_P") (pintype "passive"))
  )
	(footprint "kria-k26-devboard-footprints:RJ45_5-2337992-8_Horizontal" (layer "F.Cu")
    (at 169.69555 71.7845 180)
    (property "Author" "Antmicro")
    (property "License" "Apache-2.0")
    (property "MPN" "5-2337992-8")
    (property "Manufacturer" "TE Connectivity")
    (property "Sheetfile" "eth.kicad_sch")
    (property "Sheetname" "Ethernet")
    (property "VSD_Class" "Ethernet")
    (property "ki_description" "Modular Connector, RJ45 Jack, 1 x 1 (Port), 8P8C, Cat5e, Through Hole Mount")
    (property "ki_keywords" "RJ45, HORIZONTAL, THT, ETHERNET, CONNECTOR, FEMALE")
    (attr through_hole)
    (fp_text reference "J5" (at -1.76445 -2.7955) (layer "F.SilkS")
        (effects (font (size 0.7 0.7) (thickness 0.15)) (justify right bottom))
    )
    (fp_text value "Bus_RJ45_5-2337992-8" (at -2.6 22) (layer "F.Fab") hide
        (effects (font (size 0.7 0.7) (thickness 0.15)) (justify right bottom))
    )
    (fp_text user "License: Apache-2.0" (at -2.644 26.2) (layer "F.Fab") hide
        (effects (font (size 0.7 0.7) (thickness 0.15)) (justify right bottom))
    )
    (fp_text user "Author: Antmicro" (at -2.644 24.8) (layer "F.Fab") hide
        (effects (font (size 0.7 0.7) (thickness 0.15)) (justify right bottom))
    )
    (fp_text user "${REFERENCE}" (at -2.644 23.4) (layer "F.Fab") hide
        (effects (font (size 0.7 0.7) (thickness 0.15)) (justify right bottom))
    )
    (fp_line (start -2.363 -1.845) (end -2.363 4.48)
      (stroke (width 0.15) (type solid)) (layer "F.SilkS"))
    (fp_line (start -2.363 7.217) (end -2.363 19.771)
      (stroke (width 0.15) (type solid)) (layer "F.SilkS"))
    (fp_line (start -2.363 19.771) (end 13.791 19.771)
      (stroke (width 0.15) (type solid)) (layer "F.SilkS"))
    (fp_line (start 13.791 -1.845) (end -2.363 -1.845)
      (stroke (width 0.15) (type solid)) (layer "F.SilkS"))
    (fp_line (start 13.791 4.48) (end 13.791 -1.845)
      (stroke (width 0.15) (type solid)) (layer "F.SilkS"))
    (fp_line (start 13.791 19.771) (end 13.791 7.217)
      (stroke (width 0.15) (type solid)) (layer "F.SilkS"))
    (fp_rect (start -2.4 -1.8) (end 13.9 19.999)
      (stroke (width 0.05) (type solid)) (fill none) (layer "F.CrtYd"))
    (fp_line (start -2.237 -1.718) (end -2.237 19.644)
      (stroke (width 0.15) (type solid)) (layer "F.Fab"))
    (fp_line (start -2.237 19.644) (end 13.665 19.644)
      (stroke (width 0.15) (type solid)) (layer "F.Fab"))
    (fp_line (start 13.665 -1.718) (end -2.237 -1.718)
      (stroke (width 0.15) (type solid)) (layer "F.Fab"))
    (fp_line (start 13.665 19.644) (end 13.665 -1.718)
      (stroke (width 0.15) (type solid)) (layer "F.Fab"))
    (pad "" np_thru_hole circle (at 0 8.9 180) (size 3.25 3.25) (drill 3.25) (layers "*.Cu" "*.Mask"))
    (pad "" np_thru_hole circle (at 11.429 8.9 180) (size 3.25 3.25) (drill 3.25) (layers "*.Cu" "*.Mask"))
    (pad "1" thru_hole circle (at 0 0 180) (size 1.397 1.397) (drill 0.889) (layers "*.Cu" "*.Mask")
      (net 267 "/Ethernet/TD_A_P") (pinfunction "P1") (pintype "bidirectional"))
    (pad "2" thru_hole circle (at 1.269 2.539 180) (size 1.397 1.397) (drill 0.889) (layers "*.Cu" "*.Mask")
      (net 268 "/Ethernet/TD_A_N") (pinfunction "P2") (pintype "bidirectional"))
    (pad "3" thru_hole circle (at 2.539 0 180) (size 1.397 1.397) (drill 0.889) (layers "*.Cu" "*.Mask")
      (net 269 "/Ethernet/TD_B_P") (pinfunction "P3") (pintype "bidirectional"))
    (pad "4" thru_hole circle (at 3.809 2.539 180) (size 1.397 1.397) (drill 0.889) (layers "*.Cu" "*.Mask")
      (net 332 "Net-(J5-P4)") (pinfunction "P4") (pintype "bidirectional"))
    (pad "5" thru_hole circle (at 5.078 0 180) (size 1.397 1.397) (drill 0.889) (layers "*.Cu" "*.Mask")
      (net 333 "Net-(J5-P5)") (pinfunction "P5") (pintype "bidirectional"))
    (pad "6" thru_hole circle (at 6.349 2.539 180) (size 1.397 1.397) (drill 0.889) (layers "*.Cu" "*.Mask")
      (net 270 "/Ethernet/TD_B_N") (pinfunction "P6") (pintype "bidirectional"))
    (pad "7" thru_hole circle (at 7.618 0 180) (size 1.397 1.397) (drill 0.889) (layers "*.Cu" "*.Mask")
      (net 271 "/Ethernet/TD_C_P") (pinfunction "P7") (pintype "bidirectional"))
    (pad "8" thru_hole circle (at 8.89 2.539 180) (size 1.397 1.397) (drill 0.889) (layers "*.Cu" "*.Mask")
      (net 272 "/Ethernet/TD_C_N") (pinfunction "P8") (pintype "bidirectional"))
    (pad "9" thru_hole circle (at 10.159 0 180) (size 1.397 1.397) (drill 0.889) (layers "*.Cu" "*.Mask")
      (net 273 "/Ethernet/TD_D_P") (pinfunction "P9") (pintype "bidirectional"))
    (pad "10" thru_hole circle (at 11.429 2.539 180) (size 1.397 1.397) (drill 0.889) (layers "*.Cu" "*.Mask")
      (net 274 "/Ethernet/TD_D_N") (pinfunction "P10") (pintype "bidirectional"))
    (pad "11" thru_hole circle (at 0 5.078 180) (size 1.397 1.397) (drill 0.889) (layers "*.Cu" "*.Mask")
      (net 236 "/Ethernet/POE_VC1") (pinfunction "VC1") (pintype "bidirectional"))
    (pad "12" thru_hole circle (at 2.539 6.339 180) (size 1.397 1.397) (drill 0.889) (layers "*.Cu" "*.Mask")
      (net 235 "/Ethernet/POE_VC2") (pinfunction "VC2") (pintype "bidirectional"))
    (pad "13" thru_hole circle (at 8.89 6.339 180) (size 1.397 1.397) (drill 0.889) (layers "*.Cu" "*.Mask")
      (net 238 "/Ethernet/POE_VC3") (pinfunction "VC3") (pintype "bidirectional"))
    (pad "14" thru_hole circle (at 11.429 5.07 180) (size 1.397 1.397) (drill 0.889) (layers "*.Cu" "*.Mask")
      (net 237 "/Ethernet/POE_VC4") (pinfunction "VC4") (pintype "bidirectional"))
    (pad "15" thru_hole circle (at -0.927 12.958 180) (size 1.524 1.524) (drill 1.016) (layers "*.Cu" "*.Mask")
      (net 350 "Net-(J5-LED_GRN+)") (pinfunction "LED_GRN+") (pintype "passive"))
    (pad "16" thru_hole circle (at 1.614 12.958 180) (size 1.524 1.524) (drill 1.016) (layers "*.Cu" "*.Mask")
      (net 351 "Net-(J5-LED_GRN-)") (pinfunction "LED_GRN-") (pintype "passive"))
    (pad "17" thru_hole circle (at 9.814 12.958 180) (size 1.524 1.524) (drill 1.016) (layers "*.Cu" "*.Mask")
      (net 352 "Net-(J5-LED_YEL+)") (pinfunction "LED_YEL+") (pintype "passive"))
    (pad "18" thru_hole circle (at 12.355 12.958 180) (size 1.524 1.524) (drill 1.016) (layers "*.Cu" "*.Mask")
      (net 353 "Net-(J5-LED_YEL-)") (pinfunction "LED_YEL-") (pintype "passive"))
    (pad "19" thru_hole circle (at -2.136 5.85 180) (size 2.1 2.1) (drill 1.6) (layers "*.Cu" "*.Mask")
      (net 319 "SH_UP") (pinfunction "SHIELD") (pintype "passive"))
    (pad "20" thru_hole circle (at 13.563 5.85 180) (size 2.1082 2.1082) (drill 1.6002) (layers "*.Cu" "*.Mask")
      (net 319 "SH_UP") (pinfunction "SHIELD") (pintype "passive"))
  )
	(footprint "kria-k26-devboard-footprints:R_0402_1005Metric" (layer "F.Cu")
    (at 175.45 132.05 90)
    (descr "Resistor SMD 0402")
    (tags "resistor SMD 0402")
    (property "Author" "Antmicro")
    (property "License" "Apache-2.0")
    (property "MPN" "CR0402-FX-3162GLF")
    (property "Manufacturer" "Bourns")
    (property "Sheetfile" "dc-dc-conventers.kicad_sch")
    (property "Sheetname" "DC/DC conventers")
    (property "Tolerance" "1%")
    (property "Val" "31k6")
    (property "ki_description" "31k6 resistor in 0402 package with 1% tolerance")
    (attr smd)
    (fp_text reference "R144" (at 0.85 -1.62 180) (layer "F.SilkS")
        (effects (font (size 0.7 0.7) (thickness 0.15)) (justify left bottom))
    )
    (fp_text value "R_31k6_0402" (at 0 1.4 90) (layer "F.Fab") hide
        (effects (font (size 0.7 0.7) (thickness 0.15)) (justify left bottom))
    )
    (fp_text user "${REFERENCE}" (at -0.95 3.168 90) (layer "F.Fab") hide
        (effects (font (size 0.7 0.7) (thickness 0.15)) (justify left bottom))
    )
    (fp_text user "Author: Antmicro" (at -0.95 4.169 90) (layer "F.Fab") hide
        (effects (font (size 0.7 0.7) (thickness 0.15)) (justify left bottom))
    )
    (fp_text user "License: Apache-2.0" (at -0.95 5.169 90) (layer "F.Fab") hide
        (effects (font (size 0.7 0.7) (thickness 0.15)) (justify left bottom))
    )
    (fp_rect (start -0.93 -0.47) (end 0.93 0.47)
      (stroke (width 0.05) (type solid)) (fill none) (layer "F.CrtYd"))
    (fp_rect (start -0.5 -0.25) (end 0.5 0.25)
      (stroke (width 0.15) (type solid)) (fill none) (layer "F.Fab"))
    (pad "1" smd roundrect (at -0.485 0 90) (size 0.59 0.64) (layers "F.Cu" "F.Paste" "F.Mask") (roundrect_rratio 0.25)
      (net 770 "/Power Supply/DC/DC conventers/PL_3V3_OUT") (pintype "passive"))
    (pad "2" smd roundrect (at 0.485 0 90) (size 0.59 0.64) (layers "F.Cu" "F.Paste" "F.Mask") (roundrect_rratio 0.25)
      (net 693 "Net-(U54-FB)") (pintype "passive"))
  )
	(footprint "kria-k26-devboard-footprints:C_2220_5650Metric" (layer "F.Cu")
    (at 165.06 82.94 90)
    (descr "Capacitor SMD 2220")
    (tags "capacitor SMD 2220")
    (property "Author" "Antmicro")
    (property "Dielectric" "")
    (property "License" "Apache-2.0")
    (property "MPN" "C5750X7S2A226M280KB")
    (property "Manufacturer" "TDK")
    (property "Sheetfile" "PoE.kicad_sch")
    (property "Sheetname" "PoE")
    (property "Val" "22u/100V")
    (property "Voltage" "")
    (property "ki_description" " ")
    (attr smd)
    (fp_text reference "C172" (at -1.41 -5.93 90) (layer "F.SilkS")
        (effects (font (size 0.7 0.7) (thickness 0.15)) (justify left bottom))
    )
    (fp_text value "C_22u_100V_2220" (at 0 3.9 90) (layer "F.Fab") hide
        (effects (font (size 0.7 0.7) (thickness 0.15)) (justify left bottom))
    )
    (fp_text user "Author: Antmicro" (at -3.7 7.9 90) (layer "F.Fab") hide
        (effects (font (size 0.7 0.7) (thickness 0.15)) (justify left bottom))
    )
    (fp_text user "${REFERENCE}" (at -3.7 5.9 90) (layer "F.Fab") hide
        (effects (font (size 0.7 0.7) (thickness 0.15)) (justify left bottom))
    )
    (fp_text user "License: Apache-2.0" (at -3.7 6.9 90) (layer "F.Fab") hide
        (effects (font (size 0.7 0.7) (thickness 0.15)) (justify left bottom))
    )
    (fp_line (start -1.415 -2.61) (end 1.415 -2.61)
      (stroke (width 0.15) (type solid)) (layer "F.SilkS"))
    (fp_line (start -1.415 2.61) (end 1.415 2.61)
      (stroke (width 0.15) (type solid)) (layer "F.SilkS"))
    (fp_rect (start -3.7 -2.95) (end 3.7 2.95)
      (stroke (width 0.05) (type solid)) (fill none) (layer "F.CrtYd"))
    (fp_rect (start -2.85 -2.5) (end 2.85 2.5)
      (stroke (width 0.15) (type solid)) (fill none) (layer "F.Fab"))
    (pad "1" smd roundrect (at -2.55 0 90) (size 1.8 5.4) (layers "F.Cu" "F.Paste" "F.Mask") (roundrect_rratio 0.138889)
      (net 9 "/Power Supply/PoE/VDD_POE_IN") (pintype "passive"))
    (pad "2" smd roundrect (at 2.55 0 90) (size 1.8 5.4) (layers "F.Cu" "F.Paste" "F.Mask") (roundrect_rratio 0.138889)
      (net 11 "GNDD") (pintype "passive"))
  )
	(footprint "kria-k26-devboard-footprints:C_2220_5650Metric" (layer "F.Cu")
    (at 171.01 82.95 90)
    (descr "Capacitor SMD 2220")
    (tags "capacitor SMD 2220")
    (property "Author" "Antmicro")
    (property "Dielectric" "")
    (property "License" "Apache-2.0")
    (property "MPN" "C5750X7S2A226M280KB")
    (property "Manufacturer" "TDK")
    (property "Sheetfile" "PoE.kicad_sch")
    (property "Sheetname" "PoE")
    (property "Val" "22u/100V")
    (property "Voltage" "")
    (property "ki_description" " ")
    (attr smd)
    (fp_text reference "C175" (at -1.4 -10.9 90) (layer "F.SilkS")
        (effects (font (size 0.7 0.7) (thickness 0.15)) (justify left bottom))
    )
    (fp_text value "C_22u_100V_2220" (at 0 3.9 90) (layer "F.Fab") hide
        (effects (font (size 0.7 0.7) (thickness 0.15)) (justify left bottom))
    )
    (fp_text user "${REFERENCE}" (at -3.7 5.9 90) (layer "F.Fab") hide
        (effects (font (size 0.7 0.7) (thickness 0.15)) (justify left bottom))
    )
    (fp_text user "Author: Antmicro" (at -3.7 7.9 90) (layer "F.Fab") hide
        (effects (font (size 0.7 0.7) (thickness 0.15)) (justify left bottom))
    )
    (fp_text user "License: Apache-2.0" (at -3.7 6.9 90) (layer "F.Fab") hide
        (effects (font (size 0.7 0.7) (thickness 0.15)) (justify left bottom))
    )
    (fp_line (start -1.415 -2.61) (end 1.415 -2.61)
      (stroke (width 0.15) (type solid)) (layer "F.SilkS"))
    (fp_line (start -1.415 2.61) (end 1.415 2.61)
      (stroke (width 0.15) (type solid)) (layer "F.SilkS"))
    (fp_rect (start -3.7 -2.95) (end 3.7 2.95)
      (stroke (width 0.05) (type solid)) (fill none) (layer "F.CrtYd"))
    (fp_rect (start -2.85 -2.5) (end 2.85 2.5)
      (stroke (width 0.15) (type solid)) (fill none) (layer "F.Fab"))
    (pad "1" smd roundrect (at -2.55 0 90) (size 1.8 5.4) (layers "F.Cu" "F.Paste" "F.Mask") (roundrect_rratio 0.138889)
      (net 9 "/Power Supply/PoE/VDD_POE_IN") (pintype "passive"))
    (pad "2" smd roundrect (at 2.55 0 90) (size 1.8 5.4) (layers "F.Cu" "F.Paste" "F.Mask") (roundrect_rratio 0.138889)
      (net 11 "GNDD") (pintype "passive"))
  )
	(footprint "kria-k26-devboard-footprints:SOIC-4_W3.9mm" (layer "F.Cu")
    (at 177.79 75.63 180)
    (property "Author" "Antmicro")
    (property "License" "Apache-2.0")
    (property "MPN" "MB10S")
    (property "Manufacturer" "Multicomp Pro")
    (property "Sheetfile" "PoE.kicad_sch")
    (property "Sheetname" "PoE")
    (property "ki_description" "TVS diode")
    (property "ki_keywords" "SMT, DIODE, SEMICONDUCTOR, TVS, BRIDGE, RECTIFIER")
    (attr smd)
    (fp_text reference "D9" (at 3.6 -0.4 180) (layer "F.SilkS")
        (effects (font (size 0.7 0.7) (thickness 0.15)) (justify left bottom))
    )
    (fp_text value "MB10S" (at 0 3.6 180) (layer "F.Fab") hide
        (effects (font (size 0.7 0.7) (thickness 0.15)) (justify left bottom))
    )
    (fp_text user "${REFERENCE}" (at -4.111 5.347 180) (layer "F.Fab") hide
        (effects (font (size 0.7 0.7) (thickness 0.15)) (justify left bottom))
    )
    (fp_text user "License: Apache-2.0" (at -4.111 7.746 180) (layer "F.Fab") hide
        (effects (font (size 0.7 0.7) (thickness 0.15)) (justify left bottom))
    )
    (fp_text user "Author: Antmicro" (at -4.111 6.546 180) (layer "F.Fab") hide
        (effects (font (size 0.7 0.7) (thickness 0.15)) (justify left bottom))
    )
    (fp_line (start -2.101 2.479) (end 2.1 2.479)
      (stroke (width 0.15) (type solid)) (layer "F.SilkS"))
    (fp_line (start -2.1 -2.5) (end 2.101 -2.5)
      (stroke (width 0.15) (type solid)) (layer "F.SilkS"))
    (fp_circle (center -2.55 -2) (end -2.451 -2)
      (stroke (width 0.15) (type solid)) (fill solid) (layer "F.SilkS"))
    (fp_rect (start -3.8 -2.7) (end 3.8 2.7)
      (stroke (width 0.05) (type solid)) (fill none) (layer "F.CrtYd"))
    (fp_line (start -2.101 -2.48) (end 2.1 -2.48)
      (stroke (width 0.15) (type solid)) (layer "F.Fab"))
    (fp_line (start -2.101 2.479) (end -2.101 -2.48)
      (stroke (width 0.15) (type solid)) (layer "F.Fab"))
    (fp_line (start 2.1 -2.48) (end 2.1 2.479)
      (stroke (width 0.15) (type solid)) (layer "F.Fab"))
    (fp_line (start 2.1 2.479) (end -2.101 2.479)
      (stroke (width 0.15) (type solid)) (layer "F.Fab"))
    (pad "1" smd roundrect (at -2.851 -1.226 180) (size 1.8 1) (layers "F.Cu" "F.Paste" "F.Mask") (roundrect_rratio 0.25)
      (net 9 "/Power Supply/PoE/VDD_POE_IN") (pinfunction "1") (pintype "passive"))
    (pad "2" smd roundrect (at -2.851 1.225 180) (size 1.8 1) (layers "F.Cu" "F.Paste" "F.Mask") (roundrect_rratio 0.25)
      (net 10 "/Power Supply/PoE/VSS_POE_IN") (pinfunction "2") (pintype "passive"))
    (pad "3" smd roundrect (at 2.85 1.225 180) (size 1.8 1) (layers "F.Cu" "F.Paste" "F.Mask") (roundrect_rratio 0.25)
      (net 238 "/Ethernet/POE_VC3") (pinfunction "3") (pintype "passive"))
    (pad "4" smd roundrect (at 2.85 -1.226 180) (size 1.8 1) (layers "F.Cu" "F.Paste" "F.Mask") (roundrect_rratio 0.25)
      (net 237 "/Ethernet/POE_VC4") (pinfunction "4") (pintype "passive"))
  )
)
